FILE_TYPE=LIBRARY_PARTS;
primitive 'APX80929SAG7';
  pin
    'VCC':
      PIN_NUMBER='(3)';
      PINUSE='POWER';
      NO_LOAD_CHECK='Both';
      NO_IO_CHECK='Both';
      NO_ASSERT_CHECK='TRUE';
      NO_DIR_CHECK='TRUE';
      ALLOW_CONNECT='TRUE';
    'RESET_L':
      PIN_NUMBER='(2)';
      OUTPUT_LOAD='(1.0,-1.0)';
    'GND':
      PIN_NUMBER='(1)';
      PINUSE='POWER';
      NO_LOAD_CHECK='Both';
      NO_IO_CHECK='Both';
      NO_ASSERT_CHECK='TRUE';
      NO_DIR_CHECK='TRUE';
      ALLOW_CONNECT='TRUE';
  end_pin;
  body
    PART_NAME='APX80929SAG7';
    BODY_NAME='APX80929SAG7';
    PHYS_DES_PREFIX='U';
    CLASS='IC';
  end_body;
end_primitive;

END.
